(kicad_pcb
	(version 20260206)
	(generator "pcbnew")
	(generator_version "10.0")
	(general
		(thickness 1.6)
		(legacy_teardrops no)
	)
	(paper "A4")
	(title_block
		(title "03242023_DA0F0TMBIJ0_F0T_Motherboard_J_brd_V01_OCP.brd")
		(comment 1 "Grand Teton / footprints 3826-3831 of 6105")
	)
	(layers
		(0 "F.Cu" signal "TOP")
		(4 "In1.Cu" signal "GND")
		(6 "In2.Cu" signal "IN1")
		(8 "In3.Cu" signal "GND1")
		(10 "In4.Cu" signal "IN2")
		(12 "In5.Cu" signal "GND2")
		(14 "In6.Cu" signal "IN3")
		(16 "In7.Cu" signal "GND3")
		(18 "In8.Cu" signal "VCC")
		(20 "In9.Cu" signal "VCC1")
		(22 "In10.Cu" signal "GND4")
		(24 "In11.Cu" signal "IN4")
		(26 "In12.Cu" signal "GND5")
		(28 "In13.Cu" signal "IN5")
		(30 "In14.Cu" signal "GND6")
		(32 "In15.Cu" signal "IN6")
		(34 "In16.Cu" signal "GND7")
		(2 "B.Cu" signal "BOTTOM")
		(9 "F.Adhes" user "F.Adhesive")
		(11 "B.Adhes" user "B.Adhesive")
		(13 "F.Paste" user "Package Geometry/Pastemask Top")
		(15 "B.Paste" user "Package Geometry/Pastemask Bottom")
		(5 "F.SilkS" user "Ref Des/Silkscreen Top")
		(7 "B.SilkS" user "Ref Des/Silkscreen Bottom")
		(1 "F.Mask" user "Board Geometry/Soldermask Top")
		(3 "B.Mask" user "Board Geometry/Soldermask Bottom")
		(17 "Dwgs.User" user "User.Drawings")
		(19 "Cmts.User" user "User.Comments")
		(21 "Eco1.User" user "User.Eco1")
		(23 "Eco2.User" user "User.Eco2")
		(25 "Edge.Cuts" user "Board Geometry/Outline")
		(27 "Margin" user)
		(31 "F.CrtYd" user "Package Geometry/Place Bound Top")
		(29 "B.CrtYd" user "Package Geometry/Place Bound Bottom")
		(35 "F.Fab" user "Ref Des/Assembly Top")
		(33 "B.Fab" user "Ref Des/Assembly Bottom")
	)
	(footprint ""
		(layer "F.Cu")
		(at 309.372 -23.7744 180)
		(property "Reference" "R4786"
			(at 0 0 180)
			(layer "F.SilkS")
			(hide yes)
			(effects
				(font
					(size 1.27 1.27)
				)
			)
		)
		(property "Value" ""
			(at 0 0 180)
			(layer "F.Fab")
			(effects
				(font
					(size 1.27 1.27)
				)
			)
		)
		(duplicate_pad_numbers_are_jumpers no)
		(fp_line
			(start 0.7874 0.4064)
			(end -0.7874 0.4064)
			(stroke
				(width 0.1524)
				(type default)
			)
			(layer "F.SilkS")
		)
		(fp_line
			(start 0.7874 -0.4064)
			(end 0.7874 0.4064)
			(stroke
				(width 0.1524)
				(type default)
			)
			(layer "F.SilkS")
		)
		(fp_line
			(start -0.7874 0.4064)
			(end -0.7874 -0.4064)
			(stroke
				(width 0.1524)
				(type default)
			)
			(layer "F.SilkS")
		)
		(fp_line
			(start -0.7874 -0.4064)
			(end 0.7874 -0.4064)
			(stroke
				(width 0.1524)
				(type default)
			)
			(layer "F.SilkS")
		)
		(fp_line
			(start 0.67945 0.3048)
			(end 0.120396 0.3048)
			(stroke
				(width 0.1)
				(type default)
			)
			(layer "F.Fab")
		)
		(fp_line
			(start 0.67945 -0.3048)
			(end 0.67945 0.3048)
			(stroke
				(width 0.1)
				(type default)
			)
			(layer "F.Fab")
		)
		(fp_line
			(start 0.12065 -0.2794)
			(end 0.12065 -0.3048)
			(stroke
				(width 0.1)
				(type default)
			)
			(layer "F.Fab")
		)
		(fp_line
			(start 0.12065 -0.3048)
			(end 0.67945 -0.3048)
			(stroke
				(width 0.1)
				(type default)
			)
			(layer "F.Fab")
		)
		(fp_line
			(start 0.120396 0.3048)
			(end 0.120396 0.2794)
			(stroke
				(width 0.1)
				(type default)
			)
			(layer "F.Fab")
		)
		(fp_line
			(start 0.120396 0.2794)
			(end -0.12065 0.2794)
			(stroke
				(width 0.1)
				(type default)
			)
			(layer "F.Fab")
		)
		(fp_line
			(start -0.12065 0.3048)
			(end -0.67945 0.3048)
			(stroke
				(width 0.1)
				(type default)
			)
			(layer "F.Fab")
		)
		(fp_line
			(start -0.12065 0.2794)
			(end -0.12065 0.3048)
			(stroke
				(width 0.1)
				(type default)
			)
			(layer "F.Fab")
		)
		(fp_line
			(start -0.12065 -0.2794)
			(end 0.12065 -0.2794)
			(stroke
				(width 0.1)
				(type default)
			)
			(layer "F.Fab")
		)
		(fp_line
			(start -0.12065 -0.305054)
			(end -0.12065 -0.2794)
			(stroke
				(width 0.1)
				(type default)
			)
			(layer "F.Fab")
		)
		(fp_line
			(start -0.67945 0.3048)
			(end -0.67945 -0.305054)
			(stroke
				(width 0.1)
				(type default)
			)
			(layer "F.Fab")
		)
		(fp_line
			(start -0.67945 -0.305054)
			(end -0.12065 -0.305054)
			(stroke
				(width 0.1)
				(type default)
			)
			(layer "F.Fab")
		)
		(pad "1" smd circle
			(at -0.40005 0 180)
			(size 0 0)
			(layers "F.Cu" "F.Mask" "F.Paste")
			(net "P3V3_AUX")
		)
		(pad "2" smd circle
			(at 0.40005 0 180)
			(size 0 0)
			(layers "F.Cu" "F.Mask" "F.Paste")
			(net "DSW_PWROK_P2V5_COMP")
		)
	)
	(footprint ""
		(layer "F.Cu")
		(at 355.216714 -256.654046 -90)
		(property "Reference" "C978"
			(at 0 0 270)
			(layer "F.SilkS")
			(hide yes)
			(effects
				(font
					(size 1.27 1.27)
				)
			)
		)
		(property "Value" ""
			(at 0 0 270)
			(layer "F.Fab")
			(effects
				(font
					(size 1.27 1.27)
				)
			)
		)
		(duplicate_pad_numbers_are_jumpers no)
		(fp_line
			(start -0.7874 0.4064)
			(end -0.7874 -0.4064)
			(stroke
				(width 0.1524)
				(type default)
			)
			(layer "F.SilkS")
		)
		(fp_line
			(start 0.7874 0.4064)
			(end -0.7874 0.4064)
			(stroke
				(width 0.1524)
				(type default)
			)
			(layer "F.SilkS")
		)
		(fp_line
			(start -0.7874 -0.4064)
			(end 0.7874 -0.4064)
			(stroke
				(width 0.1524)
				(type default)
			)
			(layer "F.SilkS")
		)
		(fp_line
			(start 0.7874 -0.4064)
			(end 0.7874 0.4064)
			(stroke
				(width 0.1524)
				(type default)
			)
			(layer "F.SilkS")
		)
		(fp_line
			(start -0.67945 0.3048)
			(end -0.67945 -0.305054)
			(stroke
				(width 0.1)
				(type default)
			)
			(layer "F.Fab")
		)
		(fp_line
			(start -0.12065 0.3048)
			(end -0.67945 0.3048)
			(stroke
				(width 0.1)
				(type default)
			)
			(layer "F.Fab")
		)
		(fp_line
			(start 0.120396 0.3048)
			(end 0.120396 0.2794)
			(stroke
				(width 0.1)
				(type default)
			)
			(layer "F.Fab")
		)
		(fp_line
			(start 0.67945 0.3048)
			(end 0.120396 0.3048)
			(stroke
				(width 0.1)
				(type default)
			)
			(layer "F.Fab")
		)
		(fp_line
			(start -0.12065 0.2794)
			(end -0.12065 0.3048)
			(stroke
				(width 0.1)
				(type default)
			)
			(layer "F.Fab")
		)
		(fp_line
			(start 0.120396 0.2794)
			(end -0.12065 0.2794)
			(stroke
				(width 0.1)
				(type default)
			)
			(layer "F.Fab")
		)
		(fp_line
			(start -0.12065 -0.2794)
			(end 0.12065 -0.2794)
			(stroke
				(width 0.1)
				(type default)
			)
			(layer "F.Fab")
		)
		(fp_line
			(start 0.12065 -0.2794)
			(end 0.12065 -0.3048)
			(stroke
				(width 0.1)
				(type default)
			)
			(layer "F.Fab")
		)
		(fp_line
			(start 0.12065 -0.3048)
			(end 0.67945 -0.3048)
			(stroke
				(width 0.1)
				(type default)
			)
			(layer "F.Fab")
		)
		(fp_line
			(start 0.67945 -0.3048)
			(end 0.67945 0.3048)
			(stroke
				(width 0.1)
				(type default)
			)
			(layer "F.Fab")
		)
		(fp_line
			(start -0.67945 -0.305054)
			(end -0.12065 -0.305054)
			(stroke
				(width 0.1)
				(type default)
			)
			(layer "F.Fab")
		)
		(fp_line
			(start -0.12065 -0.305054)
			(end -0.12065 -0.2794)
			(stroke
				(width 0.1)
				(type default)
			)
			(layer "F.Fab")
		)
		(pad "1" smd circle
			(at -0.40005 0 270)
			(size 0 0)
			(layers "F.Cu" "F.Mask" "F.Paste")
			(net "PVCCIN_CPU0")
		)
		(pad "2" smd circle
			(at 0.40005 0 270)
			(size 0 0)
			(layers "F.Cu" "F.Mask" "F.Paste")
			(net "GND")
		)
	)
	(footprint ""
		(layer "F.Cu")
		(at 453.719946 -106.408728)
		(property "Reference" "R1907"
			(at 0 0 0)
			(layer "F.SilkS")
			(hide yes)
			(effects
				(font
					(size 1.27 1.27)
				)
			)
		)
		(property "Value" ""
			(at 0 0 0)
			(layer "F.Fab")
			(effects
				(font
					(size 1.27 1.27)
				)
			)
		)
		(duplicate_pad_numbers_are_jumpers no)
		(fp_line
			(start -0.7874 -0.4064)
			(end 0.7874 -0.4064)
			(stroke
				(width 0.1524)
				(type default)
			)
			(layer "F.SilkS")
		)
		(fp_line
			(start -0.7874 0.4064)
			(end -0.7874 -0.4064)
			(stroke
				(width 0.1524)
				(type default)
			)
			(layer "F.SilkS")
		)
		(fp_line
			(start 0.7874 -0.4064)
			(end 0.7874 0.4064)
			(stroke
				(width 0.1524)
				(type default)
			)
			(layer "F.SilkS")
		)
		(fp_line
			(start 0.7874 0.4064)
			(end -0.7874 0.4064)
			(stroke
				(width 0.1524)
				(type default)
			)
			(layer "F.SilkS")
		)
		(fp_line
			(start -0.67945 -0.305054)
			(end -0.12065 -0.305054)
			(stroke
				(width 0.1)
				(type default)
			)
			(layer "F.Fab")
		)
		(fp_line
			(start -0.67945 0.3048)
			(end -0.67945 -0.305054)
			(stroke
				(width 0.1)
				(type default)
			)
			(layer "F.Fab")
		)
		(fp_line
			(start -0.12065 -0.305054)
			(end -0.12065 -0.2794)
			(stroke
				(width 0.1)
				(type default)
			)
			(layer "F.Fab")
		)
		(fp_line
			(start -0.12065 -0.2794)
			(end 0.12065 -0.2794)
			(stroke
				(width 0.1)
				(type default)
			)
			(layer "F.Fab")
		)
		(fp_line
			(start -0.12065 0.2794)
			(end -0.12065 0.3048)
			(stroke
				(width 0.1)
				(type default)
			)
			(layer "F.Fab")
		)
		(fp_line
			(start -0.12065 0.3048)
			(end -0.67945 0.3048)
			(stroke
				(width 0.1)
				(type default)
			)
			(layer "F.Fab")
		)
		(fp_line
			(start 0.120396 0.2794)
			(end -0.12065 0.2794)
			(stroke
				(width 0.1)
				(type default)
			)
			(layer "F.Fab")
		)
		(fp_line
			(start 0.120396 0.3048)
			(end 0.120396 0.2794)
			(stroke
				(width 0.1)
				(type default)
			)
			(layer "F.Fab")
		)
		(fp_line
			(start 0.12065 -0.3048)
			(end 0.67945 -0.3048)
			(stroke
				(width 0.1)
				(type default)
			)
			(layer "F.Fab")
		)
		(fp_line
			(start 0.12065 -0.2794)
			(end 0.12065 -0.3048)
			(stroke
				(width 0.1)
				(type default)
			)
			(layer "F.Fab")
		)
		(fp_line
			(start 0.67945 -0.3048)
			(end 0.67945 0.3048)
			(stroke
				(width 0.1)
				(type default)
			)
			(layer "F.Fab")
		)
		(fp_line
			(start 0.67945 0.3048)
			(end 0.120396 0.3048)
			(stroke
				(width 0.1)
				(type default)
			)
			(layer "F.Fab")
		)
		(pad "1" smd circle
			(at -0.40005 0)
			(size 0 0)
			(layers "F.Cu" "F.Mask" "F.Paste")
			(net "P3V3_AUX")
		)
		(pad "2" smd circle
			(at 0.40005 0)
			(size 0 0)
			(layers "F.Cu" "F.Mask" "F.Paste")
			(net "OCP_SFF_PRSNT1_R_N")
		)
	)
	(footprint ""
		(layer "F.Cu")
		(at 123.19508 -106.238548 -90)
		(property "Reference" "R4047"
			(at 0 0 270)
			(layer "F.SilkS")
			(hide yes)
			(effects
				(font
					(size 1.27 1.27)
				)
			)
		)
		(property "Value" ""
			(at 0 0 270)
			(layer "F.Fab")
			(effects
				(font
					(size 1.27 1.27)
				)
			)
		)
		(duplicate_pad_numbers_are_jumpers no)
		(fp_line
			(start -0.7874 0.4064)
			(end -0.7874 -0.4064)
			(stroke
				(width 0.1524)
				(type default)
			)
			(layer "F.SilkS")
		)
		(fp_line
			(start 0.7874 0.4064)
			(end -0.7874 0.4064)
			(stroke
				(width 0.1524)
				(type default)
			)
			(layer "F.SilkS")
		)
		(fp_line
			(start -0.7874 -0.4064)
			(end 0.7874 -0.4064)
			(stroke
				(width 0.1524)
				(type default)
			)
			(layer "F.SilkS")
		)
		(fp_line
			(start 0.7874 -0.4064)
			(end 0.7874 0.4064)
			(stroke
				(width 0.1524)
				(type default)
			)
			(layer "F.SilkS")
		)
		(fp_line
			(start -0.67945 0.3048)
			(end -0.67945 -0.305054)
			(stroke
				(width 0.1)
				(type default)
			)
			(layer "F.Fab")
		)
		(fp_line
			(start -0.12065 0.3048)
			(end -0.67945 0.3048)
			(stroke
				(width 0.1)
				(type default)
			)
			(layer "F.Fab")
		)
		(fp_line
			(start 0.120396 0.3048)
			(end 0.120396 0.2794)
			(stroke
				(width 0.1)
				(type default)
			)
			(layer "F.Fab")
		)
		(fp_line
			(start 0.67945 0.3048)
			(end 0.120396 0.3048)
			(stroke
				(width 0.1)
				(type default)
			)
			(layer "F.Fab")
		)
		(fp_line
			(start -0.12065 0.2794)
			(end -0.12065 0.3048)
			(stroke
				(width 0.1)
				(type default)
			)
			(layer "F.Fab")
		)
		(fp_line
			(start 0.120396 0.2794)
			(end -0.12065 0.2794)
			(stroke
				(width 0.1)
				(type default)
			)
			(layer "F.Fab")
		)
		(fp_line
			(start -0.12065 -0.2794)
			(end 0.12065 -0.2794)
			(stroke
				(width 0.1)
				(type default)
			)
			(layer "F.Fab")
		)
		(fp_line
			(start 0.12065 -0.2794)
			(end 0.12065 -0.3048)
			(stroke
				(width 0.1)
				(type default)
			)
			(layer "F.Fab")
		)
		(fp_line
			(start 0.12065 -0.3048)
			(end 0.67945 -0.3048)
			(stroke
				(width 0.1)
				(type default)
			)
			(layer "F.Fab")
		)
		(fp_line
			(start 0.67945 -0.3048)
			(end 0.67945 0.3048)
			(stroke
				(width 0.1)
				(type default)
			)
			(layer "F.Fab")
		)
		(fp_line
			(start -0.67945 -0.305054)
			(end -0.12065 -0.305054)
			(stroke
				(width 0.1)
				(type default)
			)
			(layer "F.Fab")
		)
		(fp_line
			(start -0.12065 -0.305054)
			(end -0.12065 -0.2794)
			(stroke
				(width 0.1)
				(type default)
			)
			(layer "F.Fab")
		)
		(pad "1" smd circle
			(at -0.40005 0 270)
			(size 0 0)
			(layers "F.Cu" "F.Mask" "F.Paste")
			(net "RST_CPU1_DRAM_CD_PLD_LVT3_R_N")
		)
		(pad "2" smd circle
			(at 0.40005 0 270)
			(size 0 0)
			(layers "F.Cu" "F.Mask" "F.Paste")
			(net "RST_CPU1_DRAM_CD_PLD_LVT3_N")
		)
	)
	(footprint ""
		(layer "F.Cu")
		(at 115.75288 -101.793548 -90)
		(property "Reference" "R4016"
			(at 0 0 270)
			(layer "F.SilkS")
			(hide yes)
			(effects
				(font
					(size 1.27 1.27)
				)
			)
		)
		(property "Value" ""
			(at 0 0 270)
			(layer "F.Fab")
			(effects
				(font
					(size 1.27 1.27)
				)
			)
		)
		(duplicate_pad_numbers_are_jumpers no)
		(fp_line
			(start -0.7874 0.4064)
			(end -0.7874 -0.4064)
			(stroke
				(width 0.1524)
				(type default)
			)
			(layer "F.SilkS")
		)
		(fp_line
			(start 0.7874 0.4064)
			(end -0.7874 0.4064)
			(stroke
				(width 0.1524)
				(type default)
			)
			(layer "F.SilkS")
		)
		(fp_line
			(start -0.7874 -0.4064)
			(end 0.7874 -0.4064)
			(stroke
				(width 0.1524)
				(type default)
			)
			(layer "F.SilkS")
		)
		(fp_line
			(start 0.7874 -0.4064)
			(end 0.7874 0.4064)
			(stroke
				(width 0.1524)
				(type default)
			)
			(layer "F.SilkS")
		)
		(fp_line
			(start -0.67945 0.3048)
			(end -0.67945 -0.305054)
			(stroke
				(width 0.1)
				(type default)
			)
			(layer "F.Fab")
		)
		(fp_line
			(start -0.12065 0.3048)
			(end -0.67945 0.3048)
			(stroke
				(width 0.1)
				(type default)
			)
			(layer "F.Fab")
		)
		(fp_line
			(start 0.120396 0.3048)
			(end 0.120396 0.2794)
			(stroke
				(width 0.1)
				(type default)
			)
			(layer "F.Fab")
		)
		(fp_line
			(start 0.67945 0.3048)
			(end 0.120396 0.3048)
			(stroke
				(width 0.1)
				(type default)
			)
			(layer "F.Fab")
		)
		(fp_line
			(start -0.12065 0.2794)
			(end -0.12065 0.3048)
			(stroke
				(width 0.1)
				(type default)
			)
			(layer "F.Fab")
		)
		(fp_line
			(start 0.120396 0.2794)
			(end -0.12065 0.2794)
			(stroke
				(width 0.1)
				(type default)
			)
			(layer "F.Fab")
		)
		(fp_line
			(start -0.12065 -0.2794)
			(end 0.12065 -0.2794)
			(stroke
				(width 0.1)
				(type default)
			)
			(layer "F.Fab")
		)
		(fp_line
			(start 0.12065 -0.2794)
			(end 0.12065 -0.3048)
			(stroke
				(width 0.1)
				(type default)
			)
			(layer "F.Fab")
		)
		(fp_line
			(start 0.12065 -0.3048)
			(end 0.67945 -0.3048)
			(stroke
				(width 0.1)
				(type default)
			)
			(layer "F.Fab")
		)
		(fp_line
			(start 0.67945 -0.3048)
			(end 0.67945 0.3048)
			(stroke
				(width 0.1)
				(type default)
			)
			(layer "F.Fab")
		)
		(fp_line
			(start -0.67945 -0.305054)
			(end -0.12065 -0.305054)
			(stroke
				(width 0.1)
				(type default)
			)
			(layer "F.Fab")
		)
		(fp_line
			(start -0.12065 -0.305054)
			(end -0.12065 -0.2794)
			(stroke
				(width 0.1)
				(type default)
			)
			(layer "F.Fab")
		)
		(pad "1" smd circle
			(at -0.40005 0 270)
			(size 0 0)
			(layers "F.Cu" "F.Mask" "F.Paste")
			(net "P3V3")
		)
		(pad "2" smd circle
			(at 0.40005 0 270)
			(size 0 0)
			(layers "F.Cu" "F.Mask" "F.Paste")
			(net "P0V62_CPU0_ERRS_VREF")
		)
	)
	(footprint ""
		(layer "F.Cu")
		(at 388.278116 -14.25321 90)
		(property "Reference" "R444"
			(at 0 0 90)
			(layer "F.SilkS")
			(hide yes)
			(effects
				(font
					(size 1.27 1.27)
				)
			)
		)
		(property "Value" ""
			(at 0 0 90)
			(layer "F.Fab")
			(effects
				(font
					(size 1.27 1.27)
				)
			)
		)
		(duplicate_pad_numbers_are_jumpers no)
		(fp_line
			(start 0.7874 -0.4064)
			(end 0.7874 0.4064)
			(stroke
				(width 0.1524)
				(type default)
			)
			(layer "F.SilkS")
		)
		(fp_line
			(start -0.7874 -0.4064)
			(end 0.7874 -0.4064)
			(stroke
				(width 0.1524)
				(type default)
			)
			(layer "F.SilkS")
		)
		(fp_line
			(start 0.7874 0.4064)
			(end -0.7874 0.4064)
			(stroke
				(width 0.1524)
				(type default)
			)
			(layer "F.SilkS")
		)
		(fp_line
			(start -0.7874 0.4064)
			(end -0.7874 -0.4064)
			(stroke
				(width 0.1524)
				(type default)
			)
			(layer "F.SilkS")
		)
		(fp_line
			(start -0.12065 -0.305054)
			(end -0.12065 -0.2794)
			(stroke
				(width 0.1)
				(type default)
			)
			(layer "F.Fab")
		)
		(fp_line
			(start -0.67945 -0.305054)
			(end -0.12065 -0.305054)
			(stroke
				(width 0.1)
				(type default)
			)
			(layer "F.Fab")
		)
		(fp_line
			(start 0.67945 -0.3048)
			(end 0.67945 0.3048)
			(stroke
				(width 0.1)
				(type default)
			)
			(layer "F.Fab")
		)
		(fp_line
			(start 0.12065 -0.3048)
			(end 0.67945 -0.3048)
			(stroke
				(width 0.1)
				(type default)
			)
			(layer "F.Fab")
		)
		(fp_line
			(start 0.12065 -0.2794)
			(end 0.12065 -0.3048)
			(stroke
				(width 0.1)
				(type default)
			)
			(layer "F.Fab")
		)
		(fp_line
			(start -0.12065 -0.2794)
			(end 0.12065 -0.2794)
			(stroke
				(width 0.1)
				(type default)
			)
			(layer "F.Fab")
		)
		(fp_line
			(start 0.120396 0.2794)
			(end -0.12065 0.2794)
			(stroke
				(width 0.1)
				(type default)
			)
			(layer "F.Fab")
		)
		(fp_line
			(start -0.12065 0.2794)
			(end -0.12065 0.3048)
			(stroke
				(width 0.1)
				(type default)
			)
			(layer "F.Fab")
		)
		(fp_line
			(start 0.67945 0.3048)
			(end 0.120396 0.3048)
			(stroke
				(width 0.1)
				(type default)
			)
			(layer "F.Fab")
		)
		(fp_line
			(start 0.120396 0.3048)
			(end 0.120396 0.2794)
			(stroke
				(width 0.1)
				(type default)
			)
			(layer "F.Fab")
		)
		(fp_line
			(start -0.12065 0.3048)
			(end -0.67945 0.3048)
			(stroke
				(width 0.1)
				(type default)
			)
			(layer "F.Fab")
		)
		(fp_line
			(start -0.67945 0.3048)
			(end -0.67945 -0.305054)
			(stroke
				(width 0.1)
				(type default)
			)
			(layer "F.Fab")
		)
		(pad "1" smd circle
			(at -0.40005 0 90)
			(size 0 0)
			(layers "F.Cu" "F.Mask" "F.Paste")
			(net "OCP_SFF_USB2_3_DN")
		)
		(pad "2" smd circle
			(at 0.40005 0 90)
			(size 0 0)
			(layers "F.Cu" "F.Mask" "F.Paste")
			(net "USB2_3_DN")
		)
	)
)
